(kicad_pcb
	(version 20221018)
	(generator pcbnew)
	(general
    (thickness 1.62)
  )
	(paper "A4")
	(title_block
    (title "ECP5 - Datacenter Secure Control Module (DC-SCM)")
    (date "2024-07-01")
    (rev "1.2.1")
		(comment 9 "footprints 272-279 of 506")
	)
	(layers
    (0 "F.Cu" signal)
    (1 "In1.Cu" power)
    (2 "In2.Cu" signal)
    (3 "In3.Cu" power)
    (4 "In4.Cu" power)
    (5 "In5.Cu" signal)
    (6 "In6.Cu" power)
    (31 "B.Cu" signal)
    (32 "B.Adhes" user "B.Adhesive")
    (33 "F.Adhes" user "F.Adhesive")
    (34 "B.Paste" user)
    (35 "F.Paste" user)
    (36 "B.SilkS" user "B.Silkscreen")
    (37 "F.SilkS" user "F.Silkscreen")
    (38 "B.Mask" user)
    (39 "F.Mask" user)
    (40 "Dwgs.User" user "User.Drawings")
    (41 "Cmts.User" user "User.Comments")
    (42 "Eco1.User" user "User.Eco1")
    (43 "Eco2.User" user "User.Eco2")
    (44 "Edge.Cuts" user)
    (45 "Margin" user)
    (46 "B.CrtYd" user "B.Courtyard")
    (47 "F.CrtYd" user "F.Courtyard")
    (48 "B.Fab" user)
    (49 "F.Fab" user)
  )
	(footprint "antmicro-footprints:C_0402_1005Metric" (layer "B.Cu")
    (at 102.35 130.2 180)
    (descr "Capacitor SMD 0402")
    (tags "capacitor SMD 0402")
    (property "Author" "Antmicro")
    (property "Dielectric" "C0G")
    (property "License" "Apache-2.0")
    (property "MPN" "GRM1555C1H102JA01D")
    (property "Manufacturer" "Murata")
    (property "Public" "False")
    (property "Sheetfile" "fpga-power-supply.kicad_sch")
    (property "Sheetname" "FPGA power supply")
    (property "Val" "1n")
    (property "Voltage" "50V")
    (property "ki_description" "SMD Multilayer Ceramic Capacitor, 1000 pF, 50 V, 0402 [1005 Metric], ± 5%, C0G / NP0, GRM Series")
    (property "ki_keywords" "0402, SMT, CAPACITOR, PASSIVE, CERAMIC, MLCC")
    (attr smd)
    (fp_text reference "C148" (at -0.08 -20.805) (layer "B.SilkS")
        (effects (font (size 0.7 0.7) (thickness 0.127)) (justify mirror))
    )
    (fp_text value "C_1n_0402" (at 0 -1.17) (layer "B.Fab")
        (effects (font (size 1 1) (thickness 0.15)) (justify mirror))
    )
    (fp_text user "License: Apache-2.0" (at -0.939 -5.799) (layer "B.Fab") hide
        (effects (font (size 0.7 0.7) (thickness 0.15)) (justify left bottom mirror))
    )
    (fp_text user "${REFERENCE}" (at 0 0) (layer "B.Fab")
        (effects (font (size 0.25 0.25) (thickness 0.04)) (justify mirror))
    )
    (fp_text user "Author: Antmicro" (at -0.939 -3.399) (layer "B.Fab") hide
        (effects (font (size 0.7 0.7) (thickness 0.15)) (justify left bottom mirror))
    )
    (fp_rect (start -0.925 0.47) (end 0.925 -0.47)
      (stroke (width 0.05) (type default)) (fill none) (layer "B.CrtYd"))
    (fp_line (start -0.494 -0.248) (end -0.494 0.25)
      (stroke (width 0.15) (type solid)) (layer "B.Fab"))
    (fp_line (start -0.494 0.25) (end 0.504 0.25)
      (stroke (width 0.15) (type solid)) (layer "B.Fab"))
    (fp_line (start 0.504 -0.248) (end -0.494 -0.248)
      (stroke (width 0.15) (type solid)) (layer "B.Fab"))
    (fp_line (start 0.504 0.25) (end 0.504 -0.248)
      (stroke (width 0.15) (type solid)) (layer "B.Fab"))
    (pad "1" smd roundrect (at -0.48 0 180) (size 0.59 0.64) (layers "B.Cu" "B.Paste" "B.Mask") (roundrect_rratio 0.25)
      (net 1 "GND") (pintype "passive"))
    (pad "2" smd roundrect (at 0.48 0 180) (size 0.59 0.64) (layers "B.Cu" "B.Paste" "B.Mask") (roundrect_rratio 0.25)
      (net 302 "/FPGA power supply/VCCA0") (pintype "passive"))
  )
	(footprint "antmicro-footprints:C_0402_1005Metric" (layer "B.Cu")
    (at 106.55 127.4 90)
    (descr "Capacitor SMD 0402")
    (tags "capacitor SMD 0402")
    (property "Author" "Antmicro")
    (property "Dielectric" "C0G")
    (property "License" "Apache-2.0")
    (property "MPN" "GRM1555C1H102JA01D")
    (property "Manufacturer" "Murata")
    (property "Public" "False")
    (property "Sheetfile" "fpga-power-supply.kicad_sch")
    (property "Sheetname" "FPGA power supply")
    (property "Val" "1n")
    (property "Voltage" "50V")
    (property "ki_description" "SMD Multilayer Ceramic Capacitor, 1000 pF, 50 V, 0402 [1005 Metric], ± 5%, C0G / NP0, GRM Series")
    (property "ki_keywords" "0402, SMT, CAPACITOR, PASSIVE, CERAMIC, MLCC")
    (attr smd)
    (fp_text reference "C150" (at -20.765 1.13 90) (layer "B.SilkS")
        (effects (font (size 0.7 0.7) (thickness 0.127)) (justify mirror))
    )
    (fp_text value "C_1n_0402" (at 0 -1.17 90) (layer "B.Fab")
        (effects (font (size 1 1) (thickness 0.15)) (justify mirror))
    )
    (fp_text user "${REFERENCE}" (at 0 0 90) (layer "B.Fab")
        (effects (font (size 0.25 0.25) (thickness 0.04)) (justify mirror))
    )
    (fp_text user "License: Apache-2.0" (at -0.939 -5.799 270) (layer "B.Fab") hide
        (effects (font (size 0.7 0.7) (thickness 0.15)) (justify left bottom mirror))
    )
    (fp_text user "Author: Antmicro" (at -0.939 -3.399 270) (layer "B.Fab") hide
        (effects (font (size 0.7 0.7) (thickness 0.15)) (justify left bottom mirror))
    )
    (fp_rect (start -0.925 0.47) (end 0.925 -0.47)
      (stroke (width 0.05) (type default)) (fill none) (layer "B.CrtYd"))
    (fp_line (start -0.494 -0.248) (end -0.494 0.25)
      (stroke (width 0.15) (type solid)) (layer "B.Fab"))
    (fp_line (start -0.494 0.25) (end 0.504 0.25)
      (stroke (width 0.15) (type solid)) (layer "B.Fab"))
    (fp_line (start 0.504 -0.248) (end -0.494 -0.248)
      (stroke (width 0.15) (type solid)) (layer "B.Fab"))
    (fp_line (start 0.504 0.25) (end 0.504 -0.248)
      (stroke (width 0.15) (type solid)) (layer "B.Fab"))
    (pad "1" smd roundrect (at -0.48 0 90) (size 0.59 0.64) (layers "B.Cu" "B.Paste" "B.Mask") (roundrect_rratio 0.25)
      (net 1 "GND") (pintype "passive"))
    (pad "2" smd roundrect (at 0.48 0 90) (size 0.59 0.64) (layers "B.Cu" "B.Paste" "B.Mask") (roundrect_rratio 0.25)
      (net 302 "/FPGA power supply/VCCA0") (pintype "passive"))
  )
	(footprint "antmicro-footprints:C_0402_1005Metric" (layer "B.Cu")
    (at 107.55 127.4 90)
    (descr "Capacitor SMD 0402")
    (tags "capacitor SMD 0402")
    (property "Author" "Antmicro")
    (property "Dielectric" "C0G")
    (property "License" "Apache-2.0")
    (property "MPN" "GRM1555C1H102JA01D")
    (property "Manufacturer" "Murata")
    (property "Public" "False")
    (property "Sheetfile" "fpga-power-supply.kicad_sch")
    (property "Sheetname" "FPGA power supply")
    (property "Val" "1n")
    (property "Voltage" "50V")
    (property "ki_description" "SMD Multilayer Ceramic Capacitor, 1000 pF, 50 V, 0402 [1005 Metric], ± 5%, C0G / NP0, GRM Series")
    (property "ki_keywords" "0402, SMT, CAPACITOR, PASSIVE, CERAMIC, MLCC")
    (attr smd)
    (fp_text reference "C152" (at 22.8 0.05 90) (layer "B.SilkS")
        (effects (font (size 0.7 0.7) (thickness 0.127)) (justify mirror))
    )
    (fp_text value "C_1n_0402" (at 0 -1.17 90) (layer "B.Fab")
        (effects (font (size 1 1) (thickness 0.15)) (justify mirror))
    )
    (fp_text user "Author: Antmicro" (at -0.939 -3.399 270) (layer "B.Fab") hide
        (effects (font (size 0.7 0.7) (thickness 0.15)) (justify left bottom mirror))
    )
    (fp_text user "${REFERENCE}" (at 0 0 90) (layer "B.Fab")
        (effects (font (size 0.25 0.25) (thickness 0.04)) (justify mirror))
    )
    (fp_text user "License: Apache-2.0" (at -0.939 -5.799 270) (layer "B.Fab") hide
        (effects (font (size 0.7 0.7) (thickness 0.15)) (justify left bottom mirror))
    )
    (fp_rect (start -0.925 0.47) (end 0.925 -0.47)
      (stroke (width 0.05) (type default)) (fill none) (layer "B.CrtYd"))
    (fp_line (start -0.494 -0.248) (end -0.494 0.25)
      (stroke (width 0.15) (type solid)) (layer "B.Fab"))
    (fp_line (start -0.494 0.25) (end 0.504 0.25)
      (stroke (width 0.15) (type solid)) (layer "B.Fab"))
    (fp_line (start 0.504 -0.248) (end -0.494 -0.248)
      (stroke (width 0.15) (type solid)) (layer "B.Fab"))
    (fp_line (start 0.504 0.25) (end 0.504 -0.248)
      (stroke (width 0.15) (type solid)) (layer "B.Fab"))
    (pad "1" smd roundrect (at -0.48 0 90) (size 0.59 0.64) (layers "B.Cu" "B.Paste" "B.Mask") (roundrect_rratio 0.25)
      (net 1 "GND") (pintype "passive"))
    (pad "2" smd roundrect (at 0.48 0 90) (size 0.59 0.64) (layers "B.Cu" "B.Paste" "B.Mask") (roundrect_rratio 0.25)
      (net 303 "/FPGA power supply/VCCA1") (pintype "passive"))
  )
	(footprint "antmicro-footprints:C_0603_1608Metric" (layer "B.Cu")
    (at 104.4 120.945 -90)
    (descr "Capacitor SMD 0603")
    (tags "capacitor 0603")
    (property "Author" "Antmicro")
    (property "Dielectric" "")
    (property "License" "Apache-2.0")
    (property "MPN" "GRM188R60J476ME15D")
    (property "Manufacturer" "Murata")
    (property "Public" "False")
    (property "Sheetfile" "fpga-power-supply.kicad_sch")
    (property "Sheetname" "FPGA power supply")
    (property "Val" "47u")
    (property "Voltage" "")
    (property "ki_description" "SMD Multilayer Ceramic Capacitor, 47 µF, 6.3 V, 0603 [1608 Metric], ± 20%, X5R, GRM Series")
    (property "ki_keywords" "0603, SMT, CAPACITOR, PASSIVE, CERAMIC, MLCC")
    (attr smd)
    (fp_text reference "C154" (at 22.27 0.03 90) (layer "B.SilkS")
        (effects (font (size 0.7 0.7) (thickness 0.127)) (justify mirror))
    )
    (fp_text value "C_47u_0603" (at 0 -1.9 90) (layer "B.Fab")
        (effects (font (size 1 1) (thickness 0.15)) (justify mirror))
    )
    (fp_text user "${REFERENCE}" (at -1.682 -3.895 90) (layer "B.Fab") hide
        (effects (font (size 0.7 0.7) (thickness 0.15)) (justify left bottom mirror))
    )
    (fp_text user "Author: Antmicro" (at -1.682 -4.894 90) (layer "B.Fab") hide
        (effects (font (size 0.7 0.7) (thickness 0.15)) (justify left bottom mirror))
    )
    (fp_text user "License: Apache-2.0" (at -1.682 -5.895 90) (layer "B.Fab") hide
        (effects (font (size 0.7 0.7) (thickness 0.15)) (justify left bottom mirror))
    )
    (fp_line (start -0.15 -0.4) (end 0.15 -0.4)
      (stroke (width 0.15) (type solid)) (layer "B.SilkS"))
    (fp_line (start -0.15 0.4) (end 0.15 0.4)
      (stroke (width 0.15) (type solid)) (layer "B.SilkS"))
    (fp_rect (start -1.25 0.65) (end 1.25 -0.65)
      (stroke (width 0.05) (type solid)) (fill none) (layer "B.CrtYd"))
    (fp_rect (start -0.8 0.4) (end 0.8 -0.4)
      (stroke (width 0.15) (type solid)) (fill none) (layer "B.Fab"))
    (pad "1" smd roundrect (at -0.7 0 270) (size 0.8 1) (layers "B.Cu" "B.Paste" "B.Mask") (roundrect_rratio 0.2)
      (net 211 "VCC1V2") (pintype "passive"))
    (pad "2" smd roundrect (at 0.7 0 270) (size 0.8 1) (layers "B.Cu" "B.Paste" "B.Mask") (roundrect_rratio 0.2)
      (net 1 "GND") (pintype "passive"))
  )
	(footprint "antmicro-footprints:C_0603_1608Metric" (layer "B.Cu")
    (at 109.4 132.55 90)
    (descr "Capacitor SMD 0603")
    (tags "capacitor 0603")
    (property "Author" "Antmicro")
    (property "Dielectric" "")
    (property "License" "Apache-2.0")
    (property "MPN" "GRM188R60J476ME15D")
    (property "Manufacturer" "Murata")
    (property "Public" "False")
    (property "Sheetfile" "fpga-power-supply.kicad_sch")
    (property "Sheetname" "FPGA power supply")
    (property "Val" "47u")
    (property "Voltage" "")
    (property "ki_description" "SMD Multilayer Ceramic Capacitor, 47 µF, 6.3 V, 0603 [1608 Metric], ± 20%, X5R, GRM Series")
    (property "ki_keywords" "0603, SMT, CAPACITOR, PASSIVE, CERAMIC, MLCC")
    (attr smd)
    (fp_text reference "C157" (at -20.465 0.32 90) (layer "B.SilkS")
        (effects (font (size 0.7 0.7) (thickness 0.127)) (justify mirror))
    )
    (fp_text value "C_47u_0603" (at 0 -1.9 90) (layer "B.Fab")
        (effects (font (size 1 1) (thickness 0.15)) (justify mirror))
    )
    (fp_text user "Author: Antmicro" (at -1.682 -4.894 270) (layer "B.Fab") hide
        (effects (font (size 0.7 0.7) (thickness 0.15)) (justify left bottom mirror))
    )
    (fp_text user "${REFERENCE}" (at -1.682 -3.895 270) (layer "B.Fab") hide
        (effects (font (size 0.7 0.7) (thickness 0.15)) (justify left bottom mirror))
    )
    (fp_text user "License: Apache-2.0" (at -1.682 -5.895 270) (layer "B.Fab") hide
        (effects (font (size 0.7 0.7) (thickness 0.15)) (justify left bottom mirror))
    )
    (fp_line (start -0.15 -0.4) (end 0.15 -0.4)
      (stroke (width 0.15) (type solid)) (layer "B.SilkS"))
    (fp_line (start -0.15 0.4) (end 0.15 0.4)
      (stroke (width 0.15) (type solid)) (layer "B.SilkS"))
    (fp_rect (start -1.25 0.65) (end 1.25 -0.65)
      (stroke (width 0.05) (type solid)) (fill none) (layer "B.CrtYd"))
    (fp_rect (start -0.8 0.4) (end 0.8 -0.4)
      (stroke (width 0.15) (type solid)) (fill none) (layer "B.Fab"))
    (pad "1" smd roundrect (at -0.7 0 90) (size 0.8 1) (layers "B.Cu" "B.Paste" "B.Mask") (roundrect_rratio 0.2)
      (net 1 "GND") (pintype "passive"))
    (pad "2" smd roundrect (at 0.7 0 90) (size 0.8 1) (layers "B.Cu" "B.Paste" "B.Mask") (roundrect_rratio 0.2)
      (net 303 "/FPGA power supply/VCCA1") (pintype "passive"))
  )
	(footprint "antmicro-footprints:C_0603_1608Metric" (layer "B.Cu")
    (at 112.4 132.55 90)
    (descr "Capacitor SMD 0603")
    (tags "capacitor 0603")
    (property "Author" "Antmicro")
    (property "Dielectric" "")
    (property "License" "Apache-2.0")
    (property "MPN" "GRM188R60J476ME15D")
    (property "Manufacturer" "Murata")
    (property "Public" "False")
    (property "Sheetfile" "fpga-power-supply.kicad_sch")
    (property "Sheetname" "FPGA power supply")
    (property "Val" "47u")
    (property "Voltage" "")
    (property "ki_description" "SMD Multilayer Ceramic Capacitor, 47 µF, 6.3 V, 0603 [1608 Metric], ± 20%, X5R, GRM Series")
    (property "ki_keywords" "0603, SMT, CAPACITOR, PASSIVE, CERAMIC, MLCC")
    (attr smd)
    (fp_text reference "C155" (at -20.545 -0.99 90) (layer "B.SilkS")
        (effects (font (size 0.7 0.7) (thickness 0.127)) (justify mirror))
    )
    (fp_text value "C_47u_0603" (at 0 -1.9 90) (layer "B.Fab")
        (effects (font (size 1 1) (thickness 0.15)) (justify mirror))
    )
    (fp_text user "${REFERENCE}" (at -1.682 -3.895 270) (layer "B.Fab") hide
        (effects (font (size 0.7 0.7) (thickness 0.15)) (justify left bottom mirror))
    )
    (fp_text user "License: Apache-2.0" (at -1.682 -5.895 270) (layer "B.Fab") hide
        (effects (font (size 0.7 0.7) (thickness 0.15)) (justify left bottom mirror))
    )
    (fp_text user "Author: Antmicro" (at -1.682 -4.894 270) (layer "B.Fab") hide
        (effects (font (size 0.7 0.7) (thickness 0.15)) (justify left bottom mirror))
    )
    (fp_line (start -0.15 -0.4) (end 0.15 -0.4)
      (stroke (width 0.15) (type solid)) (layer "B.SilkS"))
    (fp_line (start -0.15 0.4) (end 0.15 0.4)
      (stroke (width 0.15) (type solid)) (layer "B.SilkS"))
    (fp_rect (start -1.25 0.65) (end 1.25 -0.65)
      (stroke (width 0.05) (type solid)) (fill none) (layer "B.CrtYd"))
    (fp_rect (start -0.8 0.4) (end 0.8 -0.4)
      (stroke (width 0.15) (type solid)) (fill none) (layer "B.Fab"))
    (pad "1" smd roundrect (at -0.7 0 90) (size 0.8 1) (layers "B.Cu" "B.Paste" "B.Mask") (roundrect_rratio 0.2)
      (net 1 "GND") (pintype "passive"))
    (pad "2" smd roundrect (at 0.7 0 90) (size 0.8 1) (layers "B.Cu" "B.Paste" "B.Mask") (roundrect_rratio 0.2)
      (net 304 "/FPGA power supply/VCCAUX") (pintype "passive"))
  )
	(footprint "antmicro-footprints:C_0402_1005Metric" (layer "B.Cu")
    (at 96.4 127.75 180)
    (descr "Capacitor SMD 0402")
    (tags "capacitor SMD 0402")
    (property "Author" "Antmicro")
    (property "Dielectric" "")
    (property "License" "Apache-2.0")
    (property "MPN" "GRM155R61A475MEAAD")
    (property "Manufacturer" "Murata")
    (property "Public" "False")
    (property "Sheetfile" "fpga-power-supply.kicad_sch")
    (property "Sheetname" "FPGA power supply")
    (property "Val" "4u7")
    (property "Voltage" "")
    (property "ki_description" "SMD Multilayer Ceramic Capacitor, 4.7 µF, 10 V, 0402 [1005 Metric], ± 20%, X5R, GRM Series")
    (property "ki_keywords" "0402, SMT, CAPACITOR, PASSIVE")
    (attr smd)
    (fp_text reference "C156" (at 2.45 0) (layer "B.SilkS")
        (effects (font (size 0.7 0.7) (thickness 0.127)) (justify mirror))
    )
    (fp_text value "C_4u7_0402" (at 0 -1.17) (layer "B.Fab")
        (effects (font (size 1 1) (thickness 0.15)) (justify mirror))
    )
    (fp_text user "License: Apache-2.0" (at -0.939 -5.799) (layer "B.Fab") hide
        (effects (font (size 0.7 0.7) (thickness 0.15)) (justify left bottom mirror))
    )
    (fp_text user "${REFERENCE}" (at 0 0) (layer "B.Fab")
        (effects (font (size 0.25 0.25) (thickness 0.04)) (justify mirror))
    )
    (fp_text user "Author: Antmicro" (at -0.939 -3.399) (layer "B.Fab") hide
        (effects (font (size 0.7 0.7) (thickness 0.15)) (justify left bottom mirror))
    )
    (fp_rect (start -0.925 0.47) (end 0.925 -0.47)
      (stroke (width 0.05) (type default)) (fill none) (layer "B.CrtYd"))
    (fp_line (start -0.494 -0.248) (end -0.494 0.25)
      (stroke (width 0.15) (type solid)) (layer "B.Fab"))
    (fp_line (start -0.494 0.25) (end 0.504 0.25)
      (stroke (width 0.15) (type solid)) (layer "B.Fab"))
    (fp_line (start 0.504 -0.248) (end -0.494 -0.248)
      (stroke (width 0.15) (type solid)) (layer "B.Fab"))
    (fp_line (start 0.504 0.25) (end 0.504 -0.248)
      (stroke (width 0.15) (type solid)) (layer "B.Fab"))
    (pad "1" smd roundrect (at -0.48 0 180) (size 0.59 0.64) (layers "B.Cu" "B.Paste" "B.Mask") (roundrect_rratio 0.25)
      (net 211 "VCC1V2") (pintype "passive"))
    (pad "2" smd roundrect (at 0.48 0 180) (size 0.59 0.64) (layers "B.Cu" "B.Paste" "B.Mask") (roundrect_rratio 0.25)
      (net 1 "GND") (pintype "passive"))
  )
	(footprint "antmicro-footprints:C_0402_1005Metric" (layer "B.Cu")
    (at 108.1 132.25 90)
    (descr "Capacitor SMD 0402")
    (tags "capacitor SMD 0402")
    (property "Author" "Antmicro")
    (property "Dielectric" "")
    (property "License" "Apache-2.0")
    (property "MPN" "GRM155R61A475MEAAD")
    (property "Manufacturer" "Murata")
    (property "Public" "False")
    (property "Sheetfile" "fpga-power-supply.kicad_sch")
    (property "Sheetname" "FPGA power supply")
    (property "Val" "4u7")
    (property "Voltage" "")
    (property "ki_description" "SMD Multilayer Ceramic Capacitor, 4.7 µF, 10 V, 0402 [1005 Metric], ± 20%, X5R, GRM Series")
    (property "ki_keywords" "0402, SMT, CAPACITOR, PASSIVE")
    (attr smd)
    (fp_text reference "C160" (at -20.845 0.75 90) (layer "B.SilkS")
        (effects (font (size 0.7 0.7) (thickness 0.127)) (justify mirror))
    )
    (fp_text value "C_4u7_0402" (at 0 -1.17 90) (layer "B.Fab")
        (effects (font (size 1 1) (thickness 0.15)) (justify mirror))
    )
    (fp_text user "Author: Antmicro" (at -0.939 -3.399 270) (layer "B.Fab") hide
        (effects (font (size 0.7 0.7) (thickness 0.15)) (justify left bottom mirror))
    )
    (fp_text user "License: Apache-2.0" (at -0.939 -5.799 270) (layer "B.Fab") hide
        (effects (font (size 0.7 0.7) (thickness 0.15)) (justify left bottom mirror))
    )
    (fp_text user "${REFERENCE}" (at 0 0 90) (layer "B.Fab")
        (effects (font (size 0.25 0.25) (thickness 0.04)) (justify mirror))
    )
    (fp_rect (start -0.925 0.47) (end 0.925 -0.47)
      (stroke (width 0.05) (type default)) (fill none) (layer "B.CrtYd"))
    (fp_line (start -0.494 -0.248) (end -0.494 0.25)
      (stroke (width 0.15) (type solid)) (layer "B.Fab"))
    (fp_line (start -0.494 0.25) (end 0.504 0.25)
      (stroke (width 0.15) (type solid)) (layer "B.Fab"))
    (fp_line (start 0.504 -0.248) (end -0.494 -0.248)
      (stroke (width 0.15) (type solid)) (layer "B.Fab"))
    (fp_line (start 0.504 0.25) (end 0.504 -0.248)
      (stroke (width 0.15) (type solid)) (layer "B.Fab"))
    (pad "1" smd roundrect (at -0.48 0 90) (size 0.59 0.64) (layers "B.Cu" "B.Paste" "B.Mask") (roundrect_rratio 0.25)
      (net 1 "GND") (pintype "passive"))
    (pad "2" smd roundrect (at 0.48 0 90) (size 0.59 0.64) (layers "B.Cu" "B.Paste" "B.Mask") (roundrect_rratio 0.25)
      (net 303 "/FPGA power supply/VCCA1") (pintype "passive"))
  )
)
